# S9S_MB_2U (Grand Teton) — schematic netlist excerpt (pin names and nets, part order shuffled) for the footprints in the layout excerpt that follows; sources: Cadence DE-HDL packaged netlist, KiCad conversion of 03242023_DA0F0TMBIJ0_F0T_Motherboard_J_brd_V01_OCP.brd

U331  INA230AIRGTR  EMPTY  pkg QFN16_THXI  page 251
  A1  = HSC_TYPE_ADC_A1
  A0  = HSC_TYPE_ADC_A0
  ALERT  = TP_HSC_TYPE_ADC_ALERT
  SDA  = SMB_HSC_TYPE_ADC_SDA
  SCL  = SMB_HSC_TYPE_ADC_SCL
  NC0  = NC_HSC_TYPE_NC0
  NC1  = NC_HSC_TYPE_NC1
  NC2  = NC_HSC_TYPE_NC2
  VS  = P3V3_AUX
  GND  = GND
  \bus\  = HSC_TYPE_ADC
  \in-\  = NC_HSC_TYPE_VINM
  \in+\  = NC_HSC_TYPE_VINP
  NC3  = NC_HSC_TYPE_NC3
  NC4  = NC_HSC_TYPE_NC4
  NC5  = NC_HSC_TYPE_NC5
  TH  = GND

(kicad_pcb
	(version 20260206)
	(generator "pcbnew")
	(generator_version "10.0")
	(general
		(thickness 1.6)
		(legacy_teardrops no)
	)
	(paper "A4")
	(title_block
		(title "03242023_DA0F0TMBIJ0_F0T_Motherboard_J_brd_V01_OCP.brd")
		(comment 1 "Grand Teton / footprints 247-247 of 6105")
	)
	(layers
		(0 "F.Cu" signal "TOP")
		(4 "In1.Cu" signal "GND")
		(6 "In2.Cu" signal "IN1")
		(8 "In3.Cu" signal "GND1")
		(10 "In4.Cu" signal "IN2")
		(12 "In5.Cu" signal "GND2")
		(14 "In6.Cu" signal "IN3")
		(16 "In7.Cu" signal "GND3")
		(18 "In8.Cu" signal "VCC")
		(20 "In9.Cu" signal "VCC1")
		(22 "In10.Cu" signal "GND4")
		(24 "In11.Cu" signal "IN4")
		(26 "In12.Cu" signal "GND5")
		(28 "In13.Cu" signal "IN5")
		(30 "In14.Cu" signal "GND6")
		(32 "In15.Cu" signal "IN6")
		(34 "In16.Cu" signal "GND7")
		(2 "B.Cu" signal "BOTTOM")
		(9 "F.Adhes" user "F.Adhesive")
		(11 "B.Adhes" user "B.Adhesive")
		(13 "F.Paste" user "Package Geometry/Pastemask Top")
		(15 "B.Paste" user "Package Geometry/Pastemask Bottom")
		(5 "F.SilkS" user "Ref Des/Silkscreen Top")
		(7 "B.SilkS" user "Ref Des/Silkscreen Bottom")
		(1 "F.Mask" user "Board Geometry/Soldermask Top")
		(3 "B.Mask" user "Board Geometry/Soldermask Bottom")
		(17 "Dwgs.User" user "User.Drawings")
		(19 "Cmts.User" user "User.Comments")
		(21 "Eco1.User" user "User.Eco1")
		(23 "Eco2.User" user "User.Eco2")
		(25 "Edge.Cuts" user "Board Geometry/Outline")
		(27 "Margin" user)
		(31 "F.CrtYd" user "Package Geometry/Place Bound Top")
		(29 "B.CrtYd" user "Package Geometry/Place Bound Bottom")
		(35 "F.Fab" user "Ref Des/Assembly Top")
		(33 "B.Fab" user "Ref Des/Assembly Bottom")
	)
	(footprint ""
		(layer "F.Cu")
		(at 298.368974 -412.80588)
		(property "Reference" "U331"
			(at -0.517652 -2.589022 0)
			(unlocked yes)
			(layer "F.SilkS")
			(effects
				(font
					(size 0.7874 0.5842)
					(thickness 0.1524)
				)
			)
		)
		(property "Value" ""
			(at 0 0 0)
			(layer "F.Fab")
			(effects
				(font
					(size 1.27 1.27)
				)
			)
		)
		(duplicate_pad_numbers_are_jumpers no)
		(fp_line
			(start -1.500124 -1.500124)
			(end -1.004062 -1.500124)
			(stroke
				(width 0.1524)
				(type default)
			)
			(layer "F.SilkS")
		)
		(fp_line
			(start -1.500124 -1.004062)
			(end -1.500124 -1.500124)
			(stroke
				(width 0.1524)
				(type default)
			)
			(layer "F.SilkS")
		)
		(fp_line
			(start -1.500124 1.500124)
			(end -1.500124 1.004062)
			(stroke
				(width 0.1524)
				(type default)
			)
			(layer "F.SilkS")
		)
		(fp_line
			(start -1.004062 1.500124)
			(end -1.500124 1.500124)
			(stroke
				(width 0.1524)
				(type default)
			)
			(layer "F.SilkS")
		)
		(fp_line
			(start 1.004062 -1.500124)
			(end 1.500124 -1.500124)
			(stroke
				(width 0.1524)
				(type default)
			)
			(layer "F.SilkS")
		)
		(fp_line
			(start 1.500124 -1.500124)
			(end 1.500124 -1.004062)
			(stroke
				(width 0.1524)
				(type default)
			)
			(layer "F.SilkS")
		)
		(fp_line
			(start 1.500124 1.004062)
			(end 1.500124 1.500124)
			(stroke
				(width 0.1524)
				(type default)
			)
			(layer "F.SilkS")
		)
		(fp_line
			(start 1.500124 1.500124)
			(end 1.004062 1.500124)
			(stroke
				(width 0.1524)
				(type default)
			)
			(layer "F.SilkS")
		)
		(fp_poly
			(pts
				(xy -2.1844 -1.649984) (xy -2.902966 -0.931418) (xy -1.825244 -0.572262)
			)
			(stroke
				(width 0)
				(type default)
			)
			(fill yes)
			(layer "F.SilkS")
		)
		(fp_line
			(start -1.500124 -1.500124)
			(end 1.500124 -1.500124)
			(stroke
				(width 0.1)
				(type default)
			)
			(layer "F.Fab")
		)
		(fp_line
			(start -1.500124 1.500124)
			(end -1.500124 -1.500124)
			(stroke
				(width 0.1)
				(type default)
			)
			(layer "F.Fab")
		)
		(fp_line
			(start 1.500124 -1.500124)
			(end 1.500124 1.500124)
			(stroke
				(width 0.1)
				(type default)
			)
			(layer "F.Fab")
		)
		(fp_line
			(start 1.500124 1.500124)
			(end -1.500124 1.500124)
			(stroke
				(width 0.1)
				(type default)
			)
			(layer "F.Fab")
		)
		(fp_poly
			(pts
				(xy -2.847848 -1.258062) (xy -2.847848 -0.242062) (xy -1.831848 -0.750062)
			)
			(stroke
				(width 0)
				(type default)
			)
			(fill yes)
			(layer "F.Fab")
		)
		(pad "1" smd rect
			(at -1.400048 -0.750062 270)
			(size 0.2286 0.6096)
			(layers "F.Cu" "F.Mask" "F.Paste")
			(net "HSC_TYPE_ADC_A1")
		)
		(pad "2" smd rect
			(at -1.400048 -0.249936 270)
			(size 0.2286 0.6096)
			(layers "F.Cu" "F.Mask" "F.Paste")
			(net "HSC_TYPE_ADC_A0")
		)
		(pad "3" smd rect
			(at -1.400048 0.249936 270)
			(size 0.2286 0.6096)
			(layers "F.Cu" "F.Mask" "F.Paste")
			(net "TP_HSC_TYPE_ADC_ALERT")
		)
		(pad "4" smd rect
			(at -1.400048 0.750062 270)
			(size 0.2286 0.6096)
			(layers "F.Cu" "F.Mask" "F.Paste")
			(net "SMB_HSC_TYPE_ADC_SDA")
		)
		(pad "5" smd rect
			(at -0.750062 1.400048)
			(size 0.2286 0.6096)
			(layers "F.Cu" "F.Mask" "F.Paste")
			(net "SMB_HSC_TYPE_ADC_SCL")
		)
		(pad "6" smd rect
			(at -0.249936 1.400048)
			(size 0.2286 0.6096)
			(layers "F.Cu" "F.Mask" "F.Paste")
			(net "NC_HSC_TYPE_NC0")
		)
		(pad "7" smd rect
			(at 0.249936 1.400048)
			(size 0.2286 0.6096)
			(layers "F.Cu" "F.Mask" "F.Paste")
			(net "NC_HSC_TYPE_NC1")
		)
		(pad "8" smd rect
			(at 0.750062 1.400048)
			(size 0.2286 0.6096)
			(layers "F.Cu" "F.Mask" "F.Paste")
			(net "NC_HSC_TYPE_NC2")
		)
		(pad "9" smd rect
			(at 1.400048 0.750062 270)
			(size 0.2286 0.6096)
			(layers "F.Cu" "F.Mask" "F.Paste")
			(net "P3V3_AUX")
		)
		(pad "10" smd rect
			(at 1.400048 0.249936 270)
			(size 0.2286 0.6096)
			(layers "F.Cu" "F.Mask" "F.Paste")
			(net "GND")
		)
		(pad "11" smd rect
			(at 1.400048 -0.249936 270)
			(size 0.2286 0.6096)
			(layers "F.Cu" "F.Mask" "F.Paste")
			(net "HSC_TYPE_ADC")
		)
		(pad "12" smd rect
			(at 1.400048 -0.750062 270)
			(size 0.2286 0.6096)
			(layers "F.Cu" "F.Mask" "F.Paste")
			(net "NC_HSC_TYPE_VINM")
		)
		(pad "13" smd rect
			(at 0.750062 -1.400048)
			(size 0.2286 0.6096)
			(layers "F.Cu" "F.Mask" "F.Paste")
			(net "NC_HSC_TYPE_VINP")
		)
		(pad "14" smd rect
			(at 0.249936 -1.400048)
			(size 0.2286 0.6096)
			(layers "F.Cu" "F.Mask" "F.Paste")
			(net "NC_HSC_TYPE_NC3")
		)
		(pad "15" smd rect
			(at -0.249936 -1.400048)
			(size 0.2286 0.6096)
			(layers "F.Cu" "F.Mask" "F.Paste")
			(net "NC_HSC_TYPE_NC4")
		)
		(pad "16" smd rect
			(at -0.750062 -1.400048)
			(size 0.2286 0.6096)
			(layers "F.Cu" "F.Mask" "F.Paste")
			(net "NC_HSC_TYPE_NC5")
		)
		(pad "TH" smd rect
			(at 0 0)
			(size 1.7018 1.7018)
			(layers "F.Cu" "F.Mask" "F.Paste")
			(net "GND")
		)
	)
)
